# S9S_MB_2U (Grand Teton) — schematic netlist excerpt (pin names and nets, part order shuffled) for the footprints in the layout excerpt that follows; sources: Cadence DE-HDL packaged netlist, KiCad conversion of 03242023_DA0F0TMBIJ0_F0T_Motherboard_J_brd_V01_OCP.brd

J25  SCONN288_ADR50017P130CC  SCONN288_ADR50017-P130CC IO  pkg DDR288S_1-1VXB  page 106
  VIN_BULK0  = P12V_S3_AUX_CPU1_NVDIMM
  RFU0  = TP_CHE_CPU1_DIMM1_FRU_0
  VIN_MGMT  = P3V3_AUX
  HSCL  = I3C_SPD_DDREFGH_CPU1_LVC1_SCL_R
  HSDA  = I3C_SPD_DDREFGH_CPU1_LVC1_SDA
  VSS0  = GND
  DQ0_A  = M_E_CPU1_SA_DQ<0>
  VSS1  = GND
  DQ1_A  = M_E_CPU1_SA_DQ<1>
  VSS2  = GND
  DQS0_A_T  = M_E_CPU1_SA_DQS_DP<0>
  DQS0_A_C  = M_E_CPU1_SA_DQS_DN<0>
  VSS3  = GND
  DQ4_A  = M_E_CPU1_SA_DQ<4>
  VSS4  = GND
  DQ5_A  = M_E_CPU1_SA_DQ<5>
  VSS5  = GND
  DQ8_A  = M_E_CPU1_SA_DQ<8>
  VSS6  = GND
  DQ9_A  = M_E_CPU1_SA_DQ<9>
  VSS7  = GND
  DQS1_A_T  = M_E_CPU1_SA_DQS_DP<1>
  DQS1_A_C  = M_E_CPU1_SA_DQS_DN<1>
  VSS8  = GND
  DQ12_A  = M_E_CPU1_SA_DQ<12>
  VSS9  = GND
  DQ13_A  = M_E_CPU1_SA_DQ<13>
  VSS10  = GND
  DQ16_A  = M_E_CPU1_SA_DQ<16>
  VSS11  = GND
  DQ17_A  = M_E_CPU1_SA_DQ<17>
  VSS12  = GND
  DQS2_A_T  = M_E_CPU1_SA_DQS_DP<2>
  DQS2_A_C  = M_E_CPU1_SA_DQS_DN<2>
  VSS13  = GND
  DQ20_A  = M_E_CPU1_SA_DQ<20>
  VSS14  = GND
  DQ21_A  = M_E_CPU1_SA_DQ<21>
  VSS15  = GND
  DQ24_A  = M_E_CPU1_SA_DQ<24>
  VSS16  = GND
  DQ25_A  = M_E_CPU1_SA_DQ<25>
  VSS17  = GND
  DQS3_A_T  = M_E_CPU1_SA_DQS_DP<3>
  DQS3_A_C  = M_E_CPU1_SA_DQS_DN<3>
  VSS18  = GND
  DQ28_A  = M_E_CPU1_SA_DQ<28>
  VSS19  = GND
  DQ29_A  = M_E_CPU1_SA_DQ<29>
  VSS20  = GND
  CB0_A  = M_E_CPU1_SA_CB<0>
  VSS21  = GND
  CB1_A  = M_E_CPU1_SA_CB<1>
  VSS22  = GND
  DQS4_A_T  = M_E_CPU1_SA_DQS_DP<4>
  DQS4_A_C  = M_E_CPU1_SA_DQS_DN<4>
  VSS23  = GND
  CB4_A  = M_E_CPU1_SA_CB<4>
  VSS24  = GND
  CB5_A  = M_E_CPU1_SA_CB<5>
  VSS25  = GND
  ALERT_N  = M_E_CPU1_ALERT_N
  VSS26  = GND
  CS0_A_N  = M_E_CPU1_SA_CS_N<0>
  VSS27  = GND
  CA0_A  = M_E_CPU1_SA_CA<0>
  VSS28  = GND
  CA2_A  = M_E_CPU1_SA_CA<2>
  VSS29  = GND
  CA4_A  = M_E_CPU1_SA_CA<4>
  VSS30  = GND
  CA6_A  = M_E_CPU1_SA_CA<6>
  VSS31  = GND
  PAR_A  = M_E_CPU1_SA_PAR
  VSS32  = GND
  CA0_B  = M_E_CPU1_SB_CA<0>
  VSS33  = GND
  CA2_B  = M_E_CPU1_SB_CA<2>
  VSS34  = GND
  CA4_B  = M_E_CPU1_SB_CA<4>
  VSS35  = GND
  CA6_B  = M_E_CPU1_SB_CA<6>
  VSS36  = GND
  CS0_B_N  = M_E_CPU1_SB_CS_N<0>
  VSS37  = GND
  \lbd||rsp_a_n\  = M_E_CPU1_SA_RSP<0>
  \lbs||rsp_b_n\  = M_E_CPU1_SB_RSP<0>
  VSS38  = GND
  CB4_B  = M_E_CPU1_SB_CB<4>
  VSS39  = GND
  CB5_B  = M_E_CPU1_SB_CB<5>
  VSS40  = GND
  \dqs9_b_t||tdqs9_b_t||dbi4_b_n\  = M_E_CPU1_SB_DQS_DP<9>
  \dqs9_b_c||tdqs9_b_c\  = M_E_CPU1_SB_DQS_DN<9>
  VSS41  = GND
  CB0_B  = M_E_CPU1_SB_CB<0>
  VSS42  = GND
  CB1_B  = M_E_CPU1_SB_CB<1>
  VSS43  = GND
  DQ0_B  = M_E_CPU1_SB_DQ<0>
  VSS44  = GND
  DQ1_B  = M_E_CPU1_SB_DQ<1>
  VSS45  = GND
  DQS0_B_T  = M_E_CPU1_SB_DQS_DP<0>
  DQS0_B_C  = M_E_CPU1_SB_DQS_DN<0>
  VSS46  = GND
  DQ4_B  = M_E_CPU1_SB_DQ<4>
  VSS47  = GND
  DQ5_B  = M_E_CPU1_SB_DQ<5>
  VSS48  = GND
  DQ8_B  = M_E_CPU1_SB_DQ<8>
  VSS49  = GND
  DQ9_B  = M_E_CPU1_SB_DQ<9>
  VSS50  = GND
  DQS1_B_T  = M_E_CPU1_SB_DQS_DP<1>
  DQS1_B_C  = M_E_CPU1_SB_DQS_DN<1>
  VSS51  = GND
  DQ12_B  = M_E_CPU1_SB_DQ<12>
  VSS52  = GND
  DQ13_B  = M_E_CPU1_SB_DQ<13>
  VSS53  = GND
  DQ16_B  = M_E_CPU1_SB_DQ<16>
  VSS54  = GND
  DQ17_B  = M_E_CPU1_SB_DQ<17>
  VSS55  = GND
  DQS2_B_T  = M_E_CPU1_SB_DQS_DP<2>
  DQS2_B_C  = M_E_CPU1_SB_DQS_DN<2>
  VSS56  = GND
  DQ20_B  = M_E_CPU1_SB_DQ<20>
  VSS57  = GND
  DQ21_B  = M_E_CPU1_SB_DQ<21>
  VSS58  = GND
  DQ24_B  = M_E_CPU1_SB_DQ<24>
  VSS59  = GND
  DQ25_B  = M_E_CPU1_SB_DQ<25>
  VSS60  = GND
  DQS3_B_T  = M_E_CPU1_SB_DQS_DP<3>
  DQS3_B_C  = M_E_CPU1_SB_DQS_DN<3>
  VSS61  = GND
  DQ28_B  = M_E_CPU1_SB_DQ<28>
  VSS62  = GND
  DQ29_B  = M_E_CPU1_SB_DQ<29>
  VSS63  = GND
  RFU1  = TP_CHE_CPU1_DIMM1_FRU_1
  VIN_BULK1  = P12V_S3_AUX_CPU1_NVDIMM
  VIN_BULK2  = P12V_S3_AUX_CPU1_NVDIMM
  \pwr_good||fail_n\  = PWRGD_CHE_CPU1_DIMM1
  HSA  = PD_CHE_CPU1_DIMM1_SAA
  RFU2  = TP_CHE_CPU1_DIMM1_FRU_2
  RFU3  = TP_CHE_CPU1_DIMM1_FRU_3
  VSS64  = GND
  DQ2_A  = M_E_CPU1_SA_DQ<2>
  VSS65  = GND
  DQ3_A  = M_E_CPU1_SA_DQ<3>
  VSS66  = GND
  \dqs5_a_c||tdqs5_a_c||dqs5_a_t||tdqs5_a_t\  = M_E_CPU1_SA_DQS_DN<5>
  \dqs5_a_t||tdqs5_a_t\  = M_E_CPU1_SA_DQS_DP<5>
  VSS67  = GND
  DQ6_A  = M_E_CPU1_SA_DQ<6>
  VSS68  = GND
  DQ7_A  = M_E_CPU1_SA_DQ<7>
  VSS69  = GND
  DQ10_A  = M_E_CPU1_SA_DQ<10>
  VSS70  = GND
  DQ11_A  = M_E_CPU1_SA_DQ<11>
  VSS71  = GND
  \dqs6_a_c||tdqs6_a_c||dqs6_a_t||tdqs6_a_t\  = M_E_CPU1_SA_DQS_DN<6>
  \dqs6_a_t||tdqs6_a_t\  = M_E_CPU1_SA_DQS_DP<6>
  VSS72  = GND
  DQ14_A  = M_E_CPU1_SA_DQ<14>
  VSS73  = GND
  DQ15_A  = M_E_CPU1_SA_DQ<15>
  VSS74  = GND
  DQ18_A  = M_E_CPU1_SA_DQ<18>
  VSS75  = GND
  DQ19_A  = M_E_CPU1_SA_DQ<19>
  VSS76  = GND
  \dqs7_a_c||tdqs7_a_c\  = M_E_CPU1_SA_DQS_DN<7>
  \dqs7_a_t||tdqs7_a_t\  = M_E_CPU1_SA_DQS_DP<7>
  VSS77  = GND
  DQ22_A  = M_E_CPU1_SA_DQ<22>
  VSS78  = GND
  DQ23_A  = M_E_CPU1_SA_DQ<23>
  VSS79  = GND
  DQ26_A  = M_E_CPU1_SA_DQ<26>
  VSS80  = GND
  DQ27_A  = M_E_CPU1_SA_DQ<27>
  VSS81  = GND
  \dqs8_a_c||tdqs8_a_c\  = M_E_CPU1_SA_DQS_DN<8>
  \dqs8_a_t||tdqs8_a_t\  = M_E_CPU1_SA_DQS_DP<8>
  VSS82  = GND
  DQ30_A  = M_E_CPU1_SA_DQ<30>
  VSS83  = GND
  DQ31_A  = M_E_CPU1_SA_DQ<31>
  VSS84  = GND
  CB2_A  = M_E_CPU1_SA_CB<2>
  VSS85  = GND
  CB3_A  = M_E_CPU1_SA_CB<3>
  VSS86  = GND
  \dqs9_a_c||tdqs9_a_c\  = M_E_CPU1_SA_DQS_DN<9>
  \dqs9_a_t||tdqs9_a_t\  = M_E_CPU1_SA_DQS_DP<9>
  VSS87  = GND
  CB6_A  = M_E_CPU1_SA_CB<6>
  VSS88  = GND
  CB7_A  = M_E_CPU1_SA_CB<7>
  VSS89  = GND
  RESET_N  = RST_M_EF_CPU1_FPGA_N
  VSS90  = GND
  CS1_A_N  = M_E_CPU1_SA_CS_N<1>
  VSS91  = GND
  CA1_A  = M_E_CPU1_SA_CA<1>
  VSS92  = GND
  CA3_A  = M_E_CPU1_SA_CA<3>
  VSS93  = GND
  CA5_A  = M_E_CPU1_SA_CA<5>
  VSS94  = GND
  CK_T  = M_E_CPU1_CLK_DP<0>
  CK_C  = M_E_CPU1_CLK_DN<0>
  VSS95  = GND
  RFU4  = TP_CHE_CPU1_DIMM1_FRU_4
  CA1_B  = M_E_CPU1_SB_CA<1>
  VSS96  = GND
  CA3_B  = M_E_CPU1_SB_CA<3>
  VSS97  = GND
  CA5_B  = M_E_CPU1_SB_CA<5>
  VSS98  = GND
  PAR_B  = M_E_CPU1_SB_PAR
  VSS99  = GND
  CS1_B_N  = M_E_CPU1_SB_CS_N<1>
  VSS100  = GND
  RFU5  = TP_CHE_CPU1_DIMM1_FRU_5
  RFU6  = TP_CHE_CPU1_DIMM1_FRU_6
  VSS101  = GND
  CB6_B  = M_E_CPU1_SB_CB<6>
  VSS102  = GND
  CB7_B  = M_E_CPU1_SB_CB<7>
  VSS103  = GND
  DQS4_B_C  = M_E_CPU1_SB_DQS_DN<4>
  DQS4_B_T  = M_E_CPU1_SB_DQS_DP<4>
  VSS104  = GND
  CB2_B  = M_E_CPU1_SB_CB<2>
  VSS105  = GND
  CB3_B  = M_E_CPU1_SB_CB<3>
  VSS106  = GND
  DQ2_B  = M_E_CPU1_SB_DQ<2>
  VSS107  = GND
  DQ3_B  = M_E_CPU1_SB_DQ<3>
  VSS108  = GND
  \dqs5_b_c||tdqs5_b_c\  = M_E_CPU1_SB_DQS_DN<5>
  \dqs5_b_t||tdqs5_b_t\  = M_E_CPU1_SB_DQS_DP<5>
  VSS109  = GND
  DQ6_B  = M_E_CPU1_SB_DQ<6>
  VSS110  = GND
  DQ7_B  = M_E_CPU1_SB_DQ<7>
  VSS111  = GND
  DQ10_B  = M_E_CPU1_SB_DQ<10>
  VSS112  = GND
  DQ11_B  = M_E_CPU1_SB_DQ<11>
  VSS113  = GND
  \dqs6_b_c||tdqs6_b_c\  = M_E_CPU1_SB_DQS_DN<6>
  \dqs6_b_t||tdqs6_b_t\  = M_E_CPU1_SB_DQS_DP<6>
  VSS114  = GND
  DQ14_B  = M_E_CPU1_SB_DQ<14>
  VSS115  = GND
  DQ15_B  = M_E_CPU1_SB_DQ<15>
  VSS116  = GND
  DQ18_B  = M_E_CPU1_SB_DQ<18>
  VSS117  = GND
  DQ19_B  = M_E_CPU1_SB_DQ<19>
  VSS118  = GND
  \dqs7_b_c||tdqs7_b_c\  = M_E_CPU1_SB_DQS_DN<7>
  \dqs7_b_t||tdqs7_b_t\  = M_E_CPU1_SB_DQS_DP<7>
  VSS119  = GND
  DQ22_B  = M_E_CPU1_SB_DQ<22>
  VSS120  = GND
  DQ23_B  = M_E_CPU1_SB_DQ<23>
  VSS121  = GND
  DQ26_B  = M_E_CPU1_SB_DQ<26>
  VSS122  = GND
  DQ27_B  = M_E_CPU1_SB_DQ<27>
  VSS123  = GND
  \dqs8_b_c||tdqs8_b_c\  = M_E_CPU1_SB_DQS_DN<8>
  \dqs8_b_t||tdqs8_b_t\  = M_E_CPU1_SB_DQS_DP<8>
  VSS124  = GND
  DQ30_B  = M_E_CPU1_SB_DQ<30>
  VSS125  = GND
  DQ31_B  = M_E_CPU1_SB_DQ<31>
  VSS126  = GND
  G1  = GND
  G2  = GND
  G3  = GND

(kicad_pcb
	(version 20260206)
	(generator "pcbnew")
	(generator_version "10.0")
	(general
		(thickness 1.6)
		(legacy_teardrops no)
	)
	(paper "A4")
	(title_block
		(title "03242023_DA0F0TMBIJ0_F0T_Motherboard_J_brd_V01_OCP.brd")
		(comment 1 "Grand Teton / footprint 2539 of 6105 (J25), pads 46-91 of 291")
	)
	(layers
		(0 "F.Cu" signal "TOP")
		(4 "In1.Cu" signal "GND")
		(6 "In2.Cu" signal "IN1")
		(8 "In3.Cu" signal "GND1")
		(10 "In4.Cu" signal "IN2")
		(12 "In5.Cu" signal "GND2")
		(14 "In6.Cu" signal "IN3")
		(16 "In7.Cu" signal "GND3")
		(18 "In8.Cu" signal "VCC")
		(20 "In9.Cu" signal "VCC1")
		(22 "In10.Cu" signal "GND4")
		(24 "In11.Cu" signal "IN4")
		(26 "In12.Cu" signal "GND5")
		(28 "In13.Cu" signal "IN5")
		(30 "In14.Cu" signal "GND6")
		(32 "In15.Cu" signal "IN6")
		(34 "In16.Cu" signal "GND7")
		(2 "B.Cu" signal "BOTTOM")
		(9 "F.Adhes" user "F.Adhesive")
		(11 "B.Adhes" user "B.Adhesive")
		(13 "F.Paste" user "Package Geometry/Pastemask Top")
		(15 "B.Paste" user "Package Geometry/Pastemask Bottom")
		(5 "F.SilkS" user "Ref Des/Silkscreen Top")
		(7 "B.SilkS" user "Ref Des/Silkscreen Bottom")
		(1 "F.Mask" user "Board Geometry/Soldermask Top")
		(3 "B.Mask" user "Board Geometry/Soldermask Bottom")
		(17 "Dwgs.User" user "User.Drawings")
		(19 "Cmts.User" user "User.Comments")
		(21 "Eco1.User" user "User.Eco1")
		(23 "Eco2.User" user "User.Eco2")
		(25 "Edge.Cuts" user "Board Geometry/Outline")
		(27 "Margin" user)
		(31 "F.CrtYd" user "Package Geometry/Place Bound Top")
		(29 "B.CrtYd" user "Package Geometry/Place Bound Bottom")
		(35 "F.Fab" user "Ref Des/Assembly Top")
		(33 "B.Fab" user "Ref Des/Assembly Bottom")
	)
	(footprint ""
		(layer "F.Cu")
		(at 168.40708 -258.091686)
		(property "Reference" "J25"
			(at -3.683 -81.702148 0)
			(unlocked yes)
			(layer "F.SilkS")
			(effects
				(font
					(size 0.7874 0.5842)
					(thickness 0.1524)
				)
				(justify left)
			)
		)
		(property "Value" ""
			(at 0 0 0)
			(layer "F.Fab")
			(effects
				(font
					(size 1.27 1.27)
				)
			)
		)
		(duplicate_pad_numbers_are_jumpers no)
		(pad "46" smd rect
			(at -2.050034 -25.07488 270)
			(size 0.519938 1.4986)
			(layers "F.Cu" "F.Mask" "F.Paste")
			(net "GND")
		)
		(pad "47" smd rect
			(at -2.050034 -24.224996 270)
			(size 0.519938 1.4986)
			(layers "F.Cu" "F.Mask" "F.Paste")
			(net "M_E_CPU1_SA_DQ<28>")
		)
		(pad "48" smd rect
			(at -2.050034 -23.375112 270)
			(size 0.519938 1.4986)
			(layers "F.Cu" "F.Mask" "F.Paste")
			(net "GND")
		)
		(pad "49" smd rect
			(at -2.050034 -22.524974 270)
			(size 0.519938 1.4986)
			(layers "F.Cu" "F.Mask" "F.Paste")
			(net "M_E_CPU1_SA_DQ<29>")
		)
		(pad "50" smd rect
			(at -2.050034 -21.67509 270)
			(size 0.519938 1.4986)
			(layers "F.Cu" "F.Mask" "F.Paste")
			(net "GND")
		)
		(pad "51" smd rect
			(at -2.050034 -20.824952 270)
			(size 0.519938 1.4986)
			(layers "F.Cu" "F.Mask" "F.Paste")
			(net "M_E_CPU1_SA_CB<0>")
		)
		(pad "52" smd rect
			(at -2.050034 -19.975068 270)
			(size 0.519938 1.4986)
			(layers "F.Cu" "F.Mask" "F.Paste")
			(net "GND")
		)
		(pad "53" smd rect
			(at -2.050034 -19.12493 270)
			(size 0.519938 1.4986)
			(layers "F.Cu" "F.Mask" "F.Paste")
			(net "M_E_CPU1_SA_CB<1>")
		)
		(pad "54" smd rect
			(at -2.050034 -18.275046 270)
			(size 0.519938 1.4986)
			(layers "F.Cu" "F.Mask" "F.Paste")
			(net "GND")
		)
		(pad "55" smd rect
			(at -2.050034 -17.424908 270)
			(size 0.519938 1.4986)
			(layers "F.Cu" "F.Mask" "F.Paste")
			(net "M_E_CPU1_SA_DQS_DP<4>")
		)
		(pad "56" smd rect
			(at -2.050034 -16.575024 270)
			(size 0.519938 1.4986)
			(layers "F.Cu" "F.Mask" "F.Paste")
			(net "M_E_CPU1_SA_DQS_DN<4>")
		)
		(pad "57" smd rect
			(at -2.050034 -15.724886 270)
			(size 0.519938 1.4986)
			(layers "F.Cu" "F.Mask" "F.Paste")
			(net "GND")
		)
		(pad "58" smd rect
			(at -2.050034 -14.875002 270)
			(size 0.519938 1.4986)
			(layers "F.Cu" "F.Mask" "F.Paste")
			(net "M_E_CPU1_SA_CB<4>")
		)
		(pad "59" smd rect
			(at -2.050034 -14.025118 270)
			(size 0.519938 1.4986)
			(layers "F.Cu" "F.Mask" "F.Paste")
			(net "GND")
		)
		(pad "60" smd rect
			(at -2.050034 -13.17498 270)
			(size 0.519938 1.4986)
			(layers "F.Cu" "F.Mask" "F.Paste")
			(net "M_E_CPU1_SA_CB<5>")
		)
		(pad "61" smd rect
			(at -2.050034 -12.325096 270)
			(size 0.519938 1.4986)
			(layers "F.Cu" "F.Mask" "F.Paste")
			(net "GND")
		)
		(pad "62" smd rect
			(at -2.050034 -11.474958 270)
			(size 0.519938 1.4986)
			(layers "F.Cu" "F.Mask" "F.Paste")
			(net "M_E_CPU1_ALERT_N")
		)
		(pad "63" smd rect
			(at -2.050034 -10.625074 270)
			(size 0.519938 1.4986)
			(layers "F.Cu" "F.Mask" "F.Paste")
			(net "GND")
		)
		(pad "64" smd rect
			(at -2.050034 -9.774936 270)
			(size 0.519938 1.4986)
			(layers "F.Cu" "F.Mask" "F.Paste")
			(net "M_E_CPU1_SA_CS_N<0>")
		)
		(pad "65" smd rect
			(at -2.050034 -8.925052 270)
			(size 0.519938 1.4986)
			(layers "F.Cu" "F.Mask" "F.Paste")
			(net "GND")
		)
		(pad "66" smd rect
			(at -2.050034 -8.074914 270)
			(size 0.519938 1.4986)
			(layers "F.Cu" "F.Mask" "F.Paste")
			(net "M_E_CPU1_SA_CA<0>")
		)
		(pad "67" smd rect
			(at -2.050034 -7.22503 270)
			(size 0.519938 1.4986)
			(layers "F.Cu" "F.Mask" "F.Paste")
			(net "GND")
		)
		(pad "68" smd rect
			(at -2.050034 -6.374892 270)
			(size 0.519938 1.4986)
			(layers "F.Cu" "F.Mask" "F.Paste")
			(net "M_E_CPU1_SA_CA<2>")
		)
		(pad "69" smd rect
			(at -2.050034 -5.525008 270)
			(size 0.519938 1.4986)
			(layers "F.Cu" "F.Mask" "F.Paste")
			(net "GND")
		)
		(pad "70" smd rect
			(at -2.050034 -4.675124 270)
			(size 0.519938 1.4986)
			(layers "F.Cu" "F.Mask" "F.Paste")
			(net "M_E_CPU1_SA_CA<4>")
		)
		(pad "71" smd rect
			(at -2.050034 -3.824986 270)
			(size 0.519938 1.4986)
			(layers "F.Cu" "F.Mask" "F.Paste")
			(net "GND")
		)
		(pad "72" smd rect
			(at -2.050034 -2.975102 270)
			(size 0.519938 1.4986)
			(layers "F.Cu" "F.Mask" "F.Paste")
			(net "M_E_CPU1_SA_CA<6>")
		)
		(pad "73" smd rect
			(at -2.050034 -2.124964 270)
			(size 0.519938 1.4986)
			(layers "F.Cu" "F.Mask" "F.Paste")
			(net "GND")
		)
		(pad "74" smd rect
			(at -2.050034 -1.27508 270)
			(size 0.519938 1.4986)
			(layers "F.Cu" "F.Mask" "F.Paste")
			(net "M_E_CPU1_SA_PAR")
		)
		(pad "75" smd rect
			(at -2.050034 -0.424942 270)
			(size 0.519938 1.4986)
			(layers "F.Cu" "F.Mask" "F.Paste")
			(net "GND")
		)
		(pad "76" smd rect
			(at -2.050034 5.525008 270)
			(size 0.519938 1.4986)
			(layers "F.Cu" "F.Mask" "F.Paste")
			(net "M_E_CPU1_SB_CA<0>")
		)
		(pad "77" smd rect
			(at -2.050034 6.374892 270)
			(size 0.519938 1.4986)
			(layers "F.Cu" "F.Mask" "F.Paste")
			(net "GND")
		)
		(pad "78" smd rect
			(at -2.050034 7.22503 270)
			(size 0.519938 1.4986)
			(layers "F.Cu" "F.Mask" "F.Paste")
			(net "M_E_CPU1_SB_CA<2>")
		)
		(pad "79" smd rect
			(at -2.050034 8.074914 270)
			(size 0.519938 1.4986)
			(layers "F.Cu" "F.Mask" "F.Paste")
			(net "GND")
		)
		(pad "80" smd rect
			(at -2.050034 8.925052 270)
			(size 0.519938 1.4986)
			(layers "F.Cu" "F.Mask" "F.Paste")
			(net "M_E_CPU1_SB_CA<4>")
		)
		(pad "81" smd rect
			(at -2.050034 9.774936 270)
			(size 0.519938 1.4986)
			(layers "F.Cu" "F.Mask" "F.Paste")
			(net "GND")
		)
		(pad "82" smd rect
			(at -2.050034 10.625074 270)
			(size 0.519938 1.4986)
			(layers "F.Cu" "F.Mask" "F.Paste")
			(net "M_E_CPU1_SB_CA<6>")
		)
		(pad "83" smd rect
			(at -2.050034 11.474958 270)
			(size 0.519938 1.4986)
			(layers "F.Cu" "F.Mask" "F.Paste")
			(net "GND")
		)
		(pad "84" smd rect
			(at -2.050034 12.325096 270)
			(size 0.519938 1.4986)
			(layers "F.Cu" "F.Mask" "F.Paste")
			(net "M_E_CPU1_SB_CS_N<0>")
		)
		(pad "85" smd rect
			(at -2.050034 13.17498 270)
			(size 0.519938 1.4986)
			(layers "F.Cu" "F.Mask" "F.Paste")
			(net "GND")
		)
		(pad "86" smd rect
			(at -2.050034 14.025118 270)
			(size 0.519938 1.4986)
			(layers "F.Cu" "F.Mask" "F.Paste")
			(net "M_E_CPU1_SA_RSP<0>")
		)
		(pad "87" smd rect
			(at -2.050034 14.875002 270)
			(size 0.519938 1.4986)
			(layers "F.Cu" "F.Mask" "F.Paste")
			(net "M_E_CPU1_SB_RSP<0>")
		)
		(pad "88" smd rect
			(at -2.050034 15.724886 270)
			(size 0.519938 1.4986)
			(layers "F.Cu" "F.Mask" "F.Paste")
			(net "GND")
		)
		(pad "89" smd rect
			(at -2.050034 16.575024 270)
			(size 0.519938 1.4986)
			(layers "F.Cu" "F.Mask" "F.Paste")
			(net "M_E_CPU1_SB_CB<4>")
		)
		(pad "90" smd rect
			(at -2.050034 17.424908 270)
			(size 0.519938 1.4986)
			(layers "F.Cu" "F.Mask" "F.Paste")
			(net "GND")
		)
		(pad "91" smd rect
			(at -2.050034 18.275046 270)
			(size 0.519938 1.4986)
			(layers "F.Cu" "F.Mask" "F.Paste")
			(net "M_E_CPU1_SB_CB<5>")
		)
	)
)
